(kicad_pcb
	(version 20260206)
	(generator "pcbnew")
	(generator_version "10.0")
	(general
		(thickness 1.6)
		(legacy_teardrops no)
	)
	(paper "A4")
	(title_block
		(title "04192023_DAF0TMB3IC0_F0TG_MB_C_brd_V02_OCP.brd")
		(comment 1 "Grand Teton / footprint 3975 of 8354 (U6014), pads 112-223 of 354")
	)
	(layers
		(0 "F.Cu" signal "TOP")
		(4 "In1.Cu" signal "GND")
		(6 "In2.Cu" signal "IN1")
		(8 "In3.Cu" signal "GND1")
		(10 "In4.Cu" signal "IN2")
		(12 "In5.Cu" signal "GND2")
		(14 "In6.Cu" signal "IN3")
		(16 "In7.Cu" signal "GND3")
		(18 "In8.Cu" signal "VCC")
		(20 "In9.Cu" signal "VCC1")
		(22 "In10.Cu" signal "GND4")
		(24 "In11.Cu" signal "IN4")
		(26 "In12.Cu" signal "GND5")
		(28 "In13.Cu" signal "IN5")
		(30 "In14.Cu" signal "GND6")
		(32 "In15.Cu" signal "IN6")
		(34 "In16.Cu" signal "GND7")
		(2 "B.Cu" signal "BOTTOM")
		(9 "F.Adhes" user "F.Adhesive")
		(11 "B.Adhes" user "B.Adhesive")
		(13 "F.Paste" user "Package Geometry/Pastemask Top")
		(15 "B.Paste" user "Package Geometry/Pastemask Bottom")
		(5 "F.SilkS" user "Ref Des/Silkscreen Top")
		(7 "B.SilkS" user "Ref Des/Silkscreen Bottom")
		(1 "F.Mask" user "Board Geometry/Soldermask Top")
		(3 "B.Mask" user "Board Geometry/Soldermask Bottom")
		(17 "Dwgs.User" user "User.Drawings")
		(19 "Cmts.User" user "User.Comments")
		(21 "Eco1.User" user "User.Eco1")
		(23 "Eco2.User" user "User.Eco2")
		(25 "Edge.Cuts" user "Board Geometry/Outline")
		(27 "Margin" user)
		(31 "F.CrtYd" user "Package Geometry/Place Bound Top")
		(29 "B.CrtYd" user "Package Geometry/Place Bound Bottom")
		(35 "F.Fab" user "Ref Des/Assembly Top")
		(33 "B.Fab" user "Ref Des/Assembly Bottom")
	)
	(footprint ""
		(layer "F.Cu")
		(at 56.46801 -387.342634)
		(property "Reference" "U6014"
			(at -6.735064 -7.919974 0)
			(unlocked yes)
			(layer "F.SilkS")
			(effects
				(font
					(size 0.7874 0.5842)
					(thickness 0.1524)
				)
				(justify left)
			)
		)
		(property "Value" ""
			(at 0 0 0)
			(layer "F.Fab")
			(effects
				(font
					(size 1.27 1.27)
				)
			)
		)
		(duplicate_pad_numbers_are_jumpers no)
		(pad "BV32" smd circle
			(at 1.20269 2.724912)
			(size 0.381 0.381)
			(layers "F.Cu" "F.Mask" "F.Paste")
			(net "GND")
		)
		(pad "BW2" smd circle
			(at 1.150112 -3.41884)
			(size 0.3048 0.3048)
			(layers "F.Cu" "F.Mask" "F.Paste")
			(net "GND")
		)
		(pad "BW34" smd circle
			(at 1.150112 3.420364)
			(size 0.3048 0.3048)
			(layers "F.Cu" "F.Mask" "F.Paste")
			(net "GND")
		)
		(pad "BY1" smd oval
			(at 0.849884 -3.938524)
			(size 0.254 0.3302)
			(layers "F.Cu" "F.Mask" "F.Paste")
			(net "GND")
		)
		(pad "BY35" smd oval
			(at 0.849884 3.940048)
			(size 0.254 0.3302)
			(layers "F.Cu" "F.Mask" "F.Paste")
			(net "GND")
		)
		(pad "C2" smd circle
			(at 10.750042 -3.41884)
			(size 0.3048 0.3048)
			(layers "F.Cu" "F.Mask" "F.Paste")
			(net "NCF_CPU1_P0_GND")
		)
		(pad "C34" smd circle
			(at 10.750042 3.420364)
			(size 0.3048 0.3048)
			(layers "F.Cu" "F.Mask" "F.Paste")
			(net "NCF_CPU1_P0_GND")
		)
		(pad "CA7" smd circle
			(at 0.80264 -2.12471)
			(size 0.381 0.381)
			(layers "F.Cu" "F.Mask" "F.Paste")
			(net "P5E_CPU1_P0_TX_BUF_DP<8>")
		)
		(pad "CA26" smd circle
			(at 0.80264 1.339342)
			(size 0.381 0.381)
			(layers "F.Cu" "F.Mask" "F.Paste")
			(net "P5E_CPU1_P0_RX_DP<8>")
		)
		(pad "CB2" smd circle
			(at 0.54991 -3.41884)
			(size 0.3048 0.3048)
			(layers "F.Cu" "F.Mask" "F.Paste")
			(net "P5E_CPU1_P0_RX_BUF_DN<8>")
		)
		(pad "CB34" smd circle
			(at 0.54991 3.420364)
			(size 0.3048 0.3048)
			(layers "F.Cu" "F.Mask" "F.Paste")
			(net "P5E_CPU1_P0_TX_C_DN<8>")
		)
		(pad "CC10" smd circle
			(at 0.40259 -1.431798)
			(size 0.381 0.381)
			(layers "F.Cu" "F.Mask" "F.Paste")
			(net "P5E_CPU1_P0_TX_BUF_DN<8>")
		)
		(pad "CC29" smd circle
			(at 0.40259 2.032254)
			(size 0.381 0.381)
			(layers "F.Cu" "F.Mask" "F.Paste")
			(net "P5E_CPU1_P0_RX_DN<8>")
		)
		(pad "CD1" smd oval
			(at 0.249936 -3.938524)
			(size 0.254 0.3302)
			(layers "F.Cu" "F.Mask" "F.Paste")
			(net "P5E_CPU1_P0_RX_BUF_DP<8>")
		)
		(pad "CD35" smd oval
			(at 0.249936 3.940048)
			(size 0.254 0.3302)
			(layers "F.Cu" "F.Mask" "F.Paste")
			(net "P5E_CPU1_P0_TX_C_DP<8>")
		)
		(pad "CE4" smd circle
			(at 0.00254 -2.817368)
			(size 0.381 0.381)
			(layers "F.Cu" "F.Mask" "F.Paste")
			(net "GND")
		)
		(pad "CE13" smd circle
			(at 0.00254 -0.79629)
			(size 0.3048 0.3048)
			(layers "F.Cu" "F.Mask" "F.Paste")
			(net "GND")
		)
		(pad "CE17" smd circle
			(at 0.00254 -0.296164)
			(size 0.3048 0.3048)
			(layers "F.Cu" "F.Mask" "F.Paste")
			(net "P1V8_CPU1_RT0_1A")
		)
		(pad "CE20" smd circle
			(at 0.00254 0.203708)
			(size 0.3048 0.3048)
			(layers "F.Cu" "F.Mask" "F.Paste")
			(net "P1V8_CPU1_RT0_1A")
		)
		(pad "CE22" smd circle
			(at 0.00254 0.703834)
			(size 0.3048 0.3048)
			(layers "F.Cu" "F.Mask" "F.Paste")
			(net "GND")
		)
		(pad "CE32" smd circle
			(at 0.00254 2.724912)
			(size 0.381 0.381)
			(layers "F.Cu" "F.Mask" "F.Paste")
			(net "GND")
		)
		(pad "CF2" smd circle
			(at -0.050038 -3.41884)
			(size 0.3048 0.3048)
			(layers "F.Cu" "F.Mask" "F.Paste")
			(net "GND")
		)
		(pad "CF34" smd circle
			(at -0.050038 3.420364)
			(size 0.3048 0.3048)
			(layers "F.Cu" "F.Mask" "F.Paste")
			(net "GND")
		)
		(pad "CG1" smd oval
			(at -0.350012 -3.938524)
			(size 0.254 0.3302)
			(layers "F.Cu" "F.Mask" "F.Paste")
			(net "GND")
		)
		(pad "CG35" smd oval
			(at -0.350012 3.940048)
			(size 0.254 0.3302)
			(layers "F.Cu" "F.Mask" "F.Paste")
			(net "GND")
		)
		(pad "CH7" smd circle
			(at -0.39751 -2.12471)
			(size 0.381 0.381)
			(layers "F.Cu" "F.Mask" "F.Paste")
			(net "P5E_CPU1_P0_TX_BUF_DP<7>")
		)
		(pad "CH26" smd circle
			(at -0.39751 1.339342)
			(size 0.381 0.381)
			(layers "F.Cu" "F.Mask" "F.Paste")
			(net "P5E_CPU1_P0_RX_DP<7>")
		)
		(pad "CJ2" smd circle
			(at -0.649986 -3.41884)
			(size 0.3048 0.3048)
			(layers "F.Cu" "F.Mask" "F.Paste")
			(net "P5E_CPU1_P0_RX_BUF_DN<7>")
		)
		(pad "CJ34" smd circle
			(at -0.649986 3.420364)
			(size 0.3048 0.3048)
			(layers "F.Cu" "F.Mask" "F.Paste")
			(net "P5E_CPU1_P0_TX_C_DN<7>")
		)
		(pad "CK10" smd circle
			(at -0.797306 -1.431798)
			(size 0.381 0.381)
			(layers "F.Cu" "F.Mask" "F.Paste")
			(net "P5E_CPU1_P0_TX_BUF_DN<7>")
		)
		(pad "CK29" smd circle
			(at -0.797306 2.032254)
			(size 0.381 0.381)
			(layers "F.Cu" "F.Mask" "F.Paste")
			(net "P5E_CPU1_P0_RX_DN<7>")
		)
		(pad "CL1" smd oval
			(at -0.94996 -3.938524)
			(size 0.254 0.3302)
			(layers "F.Cu" "F.Mask" "F.Paste")
			(net "P5E_CPU1_P0_RX_BUF_DP<7>")
		)
		(pad "CL35" smd oval
			(at -0.94996 3.940048)
			(size 0.254 0.3302)
			(layers "F.Cu" "F.Mask" "F.Paste")
			(net "P5E_CPU1_P0_TX_C_DP<7>")
		)
		(pad "CM4" smd circle
			(at -1.197356 -2.817368)
			(size 0.381 0.381)
			(layers "F.Cu" "F.Mask" "F.Paste")
			(net "GND")
		)
		(pad "CM13" smd circle
			(at -1.197356 -0.79629)
			(size 0.3048 0.3048)
			(layers "F.Cu" "F.Mask" "F.Paste")
			(net "GND")
		)
		(pad "CM17" smd circle
			(at -1.197356 -0.296164)
			(size 0.3048 0.3048)
			(layers "F.Cu" "F.Mask" "F.Paste")
			(net "P1V8_CPU1_RT0_1A")
		)
		(pad "CM20" smd circle
			(at -1.197356 0.203708)
			(size 0.3048 0.3048)
			(layers "F.Cu" "F.Mask" "F.Paste")
			(net "P1V8_CPU1_RT0_1A")
		)
		(pad "CM22" smd circle
			(at -1.197356 0.703834)
			(size 0.3048 0.3048)
			(layers "F.Cu" "F.Mask" "F.Paste")
			(net "GND")
		)
		(pad "CM32" smd circle
			(at -1.197356 2.724912)
			(size 0.381 0.381)
			(layers "F.Cu" "F.Mask" "F.Paste")
			(net "GND")
		)
		(pad "CN2" smd circle
			(at -1.249934 -3.41884)
			(size 0.3048 0.3048)
			(layers "F.Cu" "F.Mask" "F.Paste")
			(net "GND")
		)
		(pad "CN34" smd circle
			(at -1.249934 3.420364)
			(size 0.3048 0.3048)
			(layers "F.Cu" "F.Mask" "F.Paste")
			(net "GND")
		)
		(pad "CP1" smd oval
			(at -1.549908 -3.938524)
			(size 0.254 0.3302)
			(layers "F.Cu" "F.Mask" "F.Paste")
			(net "GND")
		)
		(pad "CP35" smd oval
			(at -1.549908 3.940048)
			(size 0.254 0.3302)
			(layers "F.Cu" "F.Mask" "F.Paste")
			(net "GND")
		)
		(pad "CR7" smd circle
			(at -1.597406 -2.12471)
			(size 0.381 0.381)
			(layers "F.Cu" "F.Mask" "F.Paste")
			(net "P5E_CPU1_P0_TX_BUF_DP<6>")
		)
		(pad "CR26" smd circle
			(at -1.597406 1.339342)
			(size 0.381 0.381)
			(layers "F.Cu" "F.Mask" "F.Paste")
			(net "P5E_CPU1_P0_RX_DP<6>")
		)
		(pad "CT2" smd circle
			(at -1.849882 -3.41884)
			(size 0.3048 0.3048)
			(layers "F.Cu" "F.Mask" "F.Paste")
			(net "P5E_CPU1_P0_RX_BUF_DN<6>")
		)
		(pad "CT34" smd circle
			(at -1.849882 3.420364)
			(size 0.3048 0.3048)
			(layers "F.Cu" "F.Mask" "F.Paste")
			(net "P5E_CPU1_P0_TX_C_DN<6>")
		)
		(pad "CU10" smd circle
			(at -1.997456 -1.431798)
			(size 0.381 0.381)
			(layers "F.Cu" "F.Mask" "F.Paste")
			(net "P5E_CPU1_P0_TX_BUF_DN<6>")
		)
		(pad "CU29" smd circle
			(at -1.997456 2.032254)
			(size 0.381 0.381)
			(layers "F.Cu" "F.Mask" "F.Paste")
			(net "P5E_CPU1_P0_RX_DN<6>")
		)
		(pad "CV1" smd oval
			(at -2.15011 -3.938524)
			(size 0.254 0.3302)
			(layers "F.Cu" "F.Mask" "F.Paste")
			(net "P5E_CPU1_P0_RX_BUF_DP<6>")
		)
		(pad "CV35" smd oval
			(at -2.15011 3.940048)
			(size 0.254 0.3302)
			(layers "F.Cu" "F.Mask" "F.Paste")
			(net "P5E_CPU1_P0_TX_C_DP<6>")
		)
		(pad "CW4" smd circle
			(at -2.397506 -2.817368)
			(size 0.381 0.381)
			(layers "F.Cu" "F.Mask" "F.Paste")
			(net "GND")
		)
		(pad "CW13" smd circle
			(at -2.397506 -0.79629)
			(size 0.3048 0.3048)
			(layers "F.Cu" "F.Mask" "F.Paste")
			(net "GND")
		)
		(pad "CW17" smd circle
			(at -2.397506 -0.296164)
			(size 0.3048 0.3048)
			(layers "F.Cu" "F.Mask" "F.Paste")
			(net "P0V9_CPU1_RT_2D")
		)
		(pad "CW20" smd circle
			(at -2.397506 0.203708)
			(size 0.3048 0.3048)
			(layers "F.Cu" "F.Mask" "F.Paste")
			(net "P0V9_CPU1_RT_2D")
		)
		(pad "CW22" smd circle
			(at -2.397506 0.703834)
			(size 0.3048 0.3048)
			(layers "F.Cu" "F.Mask" "F.Paste")
			(net "GND")
		)
		(pad "CW32" smd circle
			(at -2.397506 2.724912)
			(size 0.381 0.381)
			(layers "F.Cu" "F.Mask" "F.Paste")
			(net "GND")
		)
		(pad "CY2" smd circle
			(at -2.450084 -3.41884)
			(size 0.3048 0.3048)
			(layers "F.Cu" "F.Mask" "F.Paste")
			(net "GND")
		)
		(pad "CY34" smd circle
			(at -2.450084 3.420364)
			(size 0.3048 0.3048)
			(layers "F.Cu" "F.Mask" "F.Paste")
			(net "GND")
		)
		(pad "D1" smd oval
			(at 10.450068 -3.938524)
			(size 0.254 0.3302)
			(layers "F.Cu" "F.Mask" "F.Paste")
			(net "NCF_CPU1_P0_GND")
		)
		(pad "D35" smd oval
			(at 10.450068 3.940048)
			(size 0.254 0.3302)
			(layers "F.Cu" "F.Mask" "F.Paste")
			(net "NCF_CPU1_P0_GND")
		)
		(pad "DA1" smd oval
			(at -2.750058 -3.938524)
			(size 0.254 0.3302)
			(layers "F.Cu" "F.Mask" "F.Paste")
			(net "GND")
		)
		(pad "DA35" smd oval
			(at -2.750058 3.940048)
			(size 0.254 0.3302)
			(layers "F.Cu" "F.Mask" "F.Paste")
			(net "GND")
		)
		(pad "DB7" smd circle
			(at -2.797302 -2.12471)
			(size 0.381 0.381)
			(layers "F.Cu" "F.Mask" "F.Paste")
			(net "P5E_CPU1_P0_TX_BUF_DP<5>")
		)
		(pad "DB26" smd circle
			(at -2.797302 1.339342)
			(size 0.381 0.381)
			(layers "F.Cu" "F.Mask" "F.Paste")
			(net "P5E_CPU1_P0_RX_DP<5>")
		)
		(pad "DC2" smd circle
			(at -3.050032 -3.41884)
			(size 0.3048 0.3048)
			(layers "F.Cu" "F.Mask" "F.Paste")
			(net "P5E_CPU1_P0_RX_BUF_DN<5>")
		)
		(pad "DC34" smd circle
			(at -3.050032 3.420364)
			(size 0.3048 0.3048)
			(layers "F.Cu" "F.Mask" "F.Paste")
			(net "P5E_CPU1_P0_TX_C_DN<5>")
		)
		(pad "DD10" smd circle
			(at -3.197352 -1.431798)
			(size 0.381 0.381)
			(layers "F.Cu" "F.Mask" "F.Paste")
			(net "P5E_CPU1_P0_TX_BUF_DN<5>")
		)
		(pad "DD29" smd circle
			(at -3.197352 2.032254)
			(size 0.381 0.381)
			(layers "F.Cu" "F.Mask" "F.Paste")
			(net "P5E_CPU1_P0_RX_DN<5>")
		)
		(pad "DE1" smd oval
			(at -3.350006 -3.938524)
			(size 0.254 0.3302)
			(layers "F.Cu" "F.Mask" "F.Paste")
			(net "P5E_CPU1_P0_RX_BUF_DP<5>")
		)
		(pad "DE35" smd oval
			(at -3.350006 3.940048)
			(size 0.254 0.3302)
			(layers "F.Cu" "F.Mask" "F.Paste")
			(net "P5E_CPU1_P0_TX_C_DP<5>")
		)
		(pad "DF4" smd circle
			(at -3.597402 -2.817368)
			(size 0.381 0.381)
			(layers "F.Cu" "F.Mask" "F.Paste")
			(net "GND")
		)
		(pad "DF13" smd circle
			(at -3.597402 -0.79629)
			(size 0.3048 0.3048)
			(layers "F.Cu" "F.Mask" "F.Paste")
			(net "GND")
		)
		(pad "DF17" smd circle
			(at -3.597402 -0.296164)
			(size 0.3048 0.3048)
			(layers "F.Cu" "F.Mask" "F.Paste")
			(net "P0V9_CPU1_RT0_2A_2D")
		)
		(pad "DF20" smd circle
			(at -3.597402 0.203708)
			(size 0.3048 0.3048)
			(layers "F.Cu" "F.Mask" "F.Paste")
			(net "P0V9_CPU1_RT0_2A_2D")
		)
		(pad "DF22" smd circle
			(at -3.597402 0.703834)
			(size 0.3048 0.3048)
			(layers "F.Cu" "F.Mask" "F.Paste")
			(net "GND")
		)
		(pad "DF32" smd circle
			(at -3.597402 2.724912)
			(size 0.381 0.381)
			(layers "F.Cu" "F.Mask" "F.Paste")
			(net "GND")
		)
		(pad "DG2" smd circle
			(at -3.64998 -3.41884)
			(size 0.3048 0.3048)
			(layers "F.Cu" "F.Mask" "F.Paste")
			(net "GND")
		)
		(pad "DG34" smd circle
			(at -3.64998 3.420364)
			(size 0.3048 0.3048)
			(layers "F.Cu" "F.Mask" "F.Paste")
			(net "GND")
		)
		(pad "DH1" smd oval
			(at -3.949954 -3.938524)
			(size 0.254 0.3302)
			(layers "F.Cu" "F.Mask" "F.Paste")
			(net "GND")
		)
		(pad "DH35" smd oval
			(at -3.949954 3.940048)
			(size 0.254 0.3302)
			(layers "F.Cu" "F.Mask" "F.Paste")
			(net "GND")
		)
		(pad "DJ7" smd circle
			(at -3.997452 -2.12471)
			(size 0.381 0.381)
			(layers "F.Cu" "F.Mask" "F.Paste")
			(net "P5E_CPU1_P0_TX_BUF_DP<4>")
		)
		(pad "DJ26" smd circle
			(at -3.997452 1.339342)
			(size 0.381 0.381)
			(layers "F.Cu" "F.Mask" "F.Paste")
			(net "P5E_CPU1_P0_RX_DP<4>")
		)
		(pad "DK2" smd circle
			(at -4.249928 -3.41884)
			(size 0.3048 0.3048)
			(layers "F.Cu" "F.Mask" "F.Paste")
			(net "P5E_CPU1_P0_RX_BUF_DN<4>")
		)
		(pad "DK34" smd circle
			(at -4.249928 3.420364)
			(size 0.3048 0.3048)
			(layers "F.Cu" "F.Mask" "F.Paste")
			(net "P5E_CPU1_P0_TX_C_DN<4>")
		)
		(pad "DL10" smd circle
			(at -4.397502 -1.431798)
			(size 0.381 0.381)
			(layers "F.Cu" "F.Mask" "F.Paste")
			(net "P5E_CPU1_P0_TX_BUF_DN<4>")
		)
		(pad "DL29" smd circle
			(at -4.397502 2.032254)
			(size 0.381 0.381)
			(layers "F.Cu" "F.Mask" "F.Paste")
			(net "P5E_CPU1_P0_RX_DN<4>")
		)
		(pad "DM1" smd oval
			(at -4.549902 -3.938524)
			(size 0.254 0.3302)
			(layers "F.Cu" "F.Mask" "F.Paste")
			(net "P5E_CPU1_P0_RX_BUF_DP<4>")
		)
		(pad "DM35" smd oval
			(at -4.549902 3.940048)
			(size 0.254 0.3302)
			(layers "F.Cu" "F.Mask" "F.Paste")
			(net "P5E_CPU1_P0_TX_C_DP<4>")
		)
		(pad "DN4" smd circle
			(at -4.797298 -2.817368)
			(size 0.381 0.381)
			(layers "F.Cu" "F.Mask" "F.Paste")
			(net "GND")
		)
		(pad "DN13" smd circle
			(at -4.797298 -0.79629)
			(size 0.3048 0.3048)
			(layers "F.Cu" "F.Mask" "F.Paste")
			(net "GND")
		)
		(pad "DN17" smd circle
			(at -4.797298 -0.296164)
			(size 0.3048 0.3048)
			(layers "F.Cu" "F.Mask" "F.Paste")
			(net "P0V9_CPU1_RT0_2A")
		)
		(pad "DN20" smd circle
			(at -4.797298 0.203708)
			(size 0.3048 0.3048)
			(layers "F.Cu" "F.Mask" "F.Paste")
			(net "P0V9_CPU1_RT0_2A")
		)
		(pad "DN22" smd circle
			(at -4.797298 0.703834)
			(size 0.3048 0.3048)
			(layers "F.Cu" "F.Mask" "F.Paste")
			(net "GND")
		)
		(pad "DN32" smd circle
			(at -4.797298 2.724912)
			(size 0.381 0.381)
			(layers "F.Cu" "F.Mask" "F.Paste")
			(net "GND")
		)
		(pad "DP2" smd circle
			(at -4.849876 -3.41884)
			(size 0.3048 0.3048)
			(layers "F.Cu" "F.Mask" "F.Paste")
			(net "GND")
		)
		(pad "DP34" smd circle
			(at -4.849876 3.420364)
			(size 0.3048 0.3048)
			(layers "F.Cu" "F.Mask" "F.Paste")
			(net "GND")
		)
		(pad "DR1" smd oval
			(at -5.150104 -3.938524)
			(size 0.254 0.3302)
			(layers "F.Cu" "F.Mask" "F.Paste")
			(net "GND")
		)
		(pad "DR35" smd oval
			(at -5.150104 3.940048)
			(size 0.254 0.3302)
			(layers "F.Cu" "F.Mask" "F.Paste")
			(net "GND")
		)
		(pad "DT7" smd circle
			(at -5.197348 -2.12471)
			(size 0.381 0.381)
			(layers "F.Cu" "F.Mask" "F.Paste")
			(net "P5E_CPU1_P0_TX_BUF_DP<3>")
		)
		(pad "DT26" smd circle
			(at -5.197348 1.339342)
			(size 0.381 0.381)
			(layers "F.Cu" "F.Mask" "F.Paste")
			(net "P5E_CPU1_P0_RX_DP<3>")
		)
		(pad "DU2" smd circle
			(at -5.450078 -3.41884)
			(size 0.3048 0.3048)
			(layers "F.Cu" "F.Mask" "F.Paste")
			(net "P5E_CPU1_P0_RX_BUF_DN<3>")
		)
		(pad "DU34" smd circle
			(at -5.450078 3.420364)
			(size 0.3048 0.3048)
			(layers "F.Cu" "F.Mask" "F.Paste")
			(net "P5E_CPU1_P0_TX_C_DN<3>")
		)
		(pad "DV10" smd circle
			(at -5.597398 -1.431798)
			(size 0.381 0.381)
			(layers "F.Cu" "F.Mask" "F.Paste")
			(net "P5E_CPU1_P0_TX_BUF_DN<3>")
		)
		(pad "DV29" smd circle
			(at -5.597398 2.032254)
			(size 0.381 0.381)
			(layers "F.Cu" "F.Mask" "F.Paste")
			(net "P5E_CPU1_P0_RX_DN<3>")
		)
		(pad "DW1" smd oval
			(at -5.750052 -3.938524)
			(size 0.254 0.3302)
			(layers "F.Cu" "F.Mask" "F.Paste")
			(net "P5E_CPU1_P0_RX_BUF_DP<3>")
		)
		(pad "DW35" smd oval
			(at -5.750052 3.940048)
			(size 0.254 0.3302)
			(layers "F.Cu" "F.Mask" "F.Paste")
			(net "P5E_CPU1_P0_TX_C_DP<3>")
		)
		(pad "DY4" smd circle
			(at -5.997448 -2.817368)
			(size 0.381 0.381)
			(layers "F.Cu" "F.Mask" "F.Paste")
			(net "GND")
		)
		(pad "DY13" smd circle
			(at -5.997448 -0.79629)
			(size 0.3048 0.3048)
			(layers "F.Cu" "F.Mask" "F.Paste")
			(net "GND")
		)
		(pad "DY17" smd circle
			(at -5.997448 -0.296164)
			(size 0.3048 0.3048)
			(layers "F.Cu" "F.Mask" "F.Paste")
			(net "P0V9_CPU1_RT0_2A")
		)
		(pad "DY20" smd circle
			(at -5.997448 0.203708)
			(size 0.3048 0.3048)
			(layers "F.Cu" "F.Mask" "F.Paste")
			(net "P0V9_CPU1_RT0_2A")
		)
		(pad "DY22" smd circle
			(at -5.997448 0.703834)
			(size 0.3048 0.3048)
			(layers "F.Cu" "F.Mask" "F.Paste")
			(net "GND")
		)
	)
)
